(kicad_pcb
	(version 20241229)
	(generator "pcbnew")
	(generator_version "9.0")
	(general
		(thickness 1.62)
		(legacy_teardrops no)
	)
	(paper "A3")
	(title_block
		(title "COM Express 7 Baseboard")
		(date "2025-02-04")
		(rev "1.1.2")
		(company "Antmicro Ltd")
		(comment 1 "www.antmicro.com")
		(comment 9 "footprints 127-131 of 802")
	)
	(layers
		(0 "F.Cu" signal)
		(4 "In1.Cu" signal)
		(6 "In2.Cu" signal)
		(8 "In3.Cu" signal)
		(10 "In4.Cu" signal)
		(12 "In5.Cu" signal)
		(14 "In6.Cu" signal)
		(2 "B.Cu" signal)
		(9 "F.Adhes" user "F.Adhesive")
		(11 "B.Adhes" user "B.Adhesive")
		(13 "F.Paste" user)
		(15 "B.Paste" user)
		(5 "F.SilkS" user "F.Silkscreen")
		(7 "B.SilkS" user "B.Silkscreen")
		(1 "F.Mask" user)
		(3 "B.Mask" user)
		(17 "Dwgs.User" user "User.Drawings")
		(19 "Cmts.User" user "User.Comments")
		(21 "Eco1.User" user "User.Eco1")
		(23 "Eco2.User" user "User.Eco2")
		(25 "Edge.Cuts" user)
		(27 "Margin" user)
		(31 "F.CrtYd" user "F.Courtyard")
		(29 "B.CrtYd" user "B.Courtyard")
		(35 "F.Fab" user)
		(33 "B.Fab" user)
	)
	(footprint "antmicro-footprints:LED_0603_1608Metric_G"
		(layer "F.Cu")
		(at 112.4 69.86 90)
		(descr "LED SMD 0603 Green")
		(tags "LED SMD 0603 Green")
		(property "Reference" "D11"
			(at -3.4 0.4 90)
			(layer "F.SilkS")
			(effects
				(font
					(size 0.7 0.7)
					(thickness 0.15)
				)
				(justify left bottom)
			)
		)
		(property "Value" "LED_G_0603_LTST-C190GKT"
			(at -0.001 1.599 90)
			(layer "F.Fab")
			(effects
				(font
					(size 0.7 0.7)
					(thickness 0.15)
				)
				(justify left bottom)
			)
		)
		(property "Datasheet" "https://media.digikey.com/pdf/Data%20Sheets/Lite-On%20PDFs/LTST-C190GKT.pdf"
			(at 0 0 90)
			(layer "F.Fab")
			(hide yes)
			(effects
				(font
					(size 1.27 1.27)
					(thickness 0.15)
				)
			)
		)
		(property "Author" "Antmicro"
			(at 182.26 -42.54 0)
			(layer "F.Fab")
			(hide yes)
			(effects
				(font
					(size 1 1)
					(thickness 0.15)
				)
			)
		)
		(property "Color" "Green"
			(at 182.26 -42.54 0)
			(layer "F.Fab")
			(hide yes)
			(effects
				(font
					(size 1 1)
					(thickness 0.15)
				)
			)
		)
		(property "License" "Apache-2.0"
			(at 182.26 -42.54 0)
			(layer "F.Fab")
			(hide yes)
			(effects
				(font
					(size 1 1)
					(thickness 0.15)
				)
			)
		)
		(property "MPN" "LTST-C190GKT"
			(at 182.26 -42.54 0)
			(layer "F.Fab")
			(hide yes)
			(effects
				(font
					(size 1 1)
					(thickness 0.15)
				)
			)
		)
		(property "Manufacturer" "Lite-On"
			(at 182.26 -42.54 0)
			(layer "F.Fab")
			(hide yes)
			(effects
				(font
					(size 1 1)
					(thickness 0.15)
				)
			)
		)
		(property "Public" "False"
			(at 182.26 -42.54 0)
			(layer "F.Fab")
			(hide yes)
			(effects
				(font
					(size 1 1)
					(thickness 0.15)
				)
			)
		)
		(sheetname "USB-C console")
		(sheetfile "usb-c_console.kicad_sch")
		(attr smd)
		(fp_line
			(start 0.22 -0.35)
			(end -0.22 -0.35)
			(stroke
				(width 0.15)
				(type solid)
			)
			(layer "F.SilkS")
		)
		(fp_line
			(start -1.18 -0.319)
			(end -1.18 0.321)
			(stroke
				(width 0.15)
				(type solid)
			)
			(layer "F.SilkS")
		)
		(fp_line
			(start 0.105328 0.001008)
			(end 0.24 0.001)
			(stroke
				(width 0.1)
				(type solid)
			)
			(layer "F.SilkS")
		)
		(fp_line
			(start -0.094672 0.001008)
			(end 0.105328 -0.198992)
			(stroke
				(width 0.1)
				(type solid)
			)
			(layer "F.SilkS")
		)
		(fp_line
			(start -0.094672 0.001008)
			(end -0.24 0.001008)
			(stroke
				(width 0.1)
				(type solid)
			)
			(layer "F.SilkS")
		)
		(fp_line
			(start 0.105328 0.201008)
			(end 0.105328 -0.198992)
			(stroke
				(width 0.1)
				(type solid)
			)
			(layer "F.SilkS")
		)
		(fp_line
			(start 0.105328 0.201008)
			(end -0.094672 0.001008)
			(stroke
				(width 0.1)
				(type solid)
			)
			(layer "F.SilkS")
		)
		(fp_line
			(start -0.094672 0.201008)
			(end -0.094672 -0.198992)
			(stroke
				(width 0.1)
				(type solid)
			)
			(layer "F.SilkS")
		)
		(fp_line
			(start 0.22 0.35)
			(end -0.22 0.35)
			(stroke
				(width 0.15)
				(type solid)
			)
			(layer "F.SilkS")
		)
		(fp_rect
			(start 1.25 0.65)
			(end -1.25 -0.65)
			(stroke
				(width 0.05)
				(type solid)
			)
			(fill no)
			(layer "F.CrtYd")
		)
		(fp_line
			(start 0.201 -0.202)
			(end -0.101 0)
			(stroke
				(width 0.15)
				(type solid)
			)
			(layer "F.Fab")
		)
		(fp_line
			(start -0.199 -0.202)
			(end -0.199 0.1)
			(stroke
				(width 0.15)
				(type solid)
			)
			(layer "F.Fab")
		)
		(fp_line
			(start 0.599 0)
			(end 0.201 0)
			(stroke
				(width 0.15)
				(type solid)
			)
			(layer "F.Fab")
		)
		(fp_line
			(start 0.201 0)
			(end 0.201 -0.202)
			(stroke
				(width 0.15)
				(type solid)
			)
			(layer "F.Fab")
		)
		(fp_line
			(start -0.101 0)
			(end 0.201 0.2)
			(stroke
				(width 0.15)
				(type solid)
			)
			(layer "F.Fab")
		)
		(fp_line
			(start -0.199 0)
			(end -0.597 0)
			(stroke
				(width 0.15)
				(type solid)
			)
			(layer "F.Fab")
		)
		(fp_line
			(start 0.201 0.2)
			(end 0.201 0)
			(stroke
				(width 0.15)
				(type solid)
			)
			(layer "F.Fab")
		)
		(fp_line
			(start -0.199 0.2)
			(end -0.199 0.1)
			(stroke
				(width 0.15)
				(type solid)
			)
			(layer "F.Fab")
		)
		(fp_rect
			(start 0.848 0.4)
			(end -0.85 -0.402)
			(stroke
				(width 0.15)
				(type solid)
			)
			(fill no)
			(layer "F.Fab")
		)
		(pad "1" smd roundrect
			(at -0.7 0 270)
			(size 0.8 1)
			(layers "F.Cu" "F.Mask" "F.Paste")
			(roundrect_rratio 0.2)
			(net 127 "/USB-C console/FTDI_LED_RX")
			(pinfunction "C")
			(pintype "passive")
			(teardrops
				(best_length_ratio 0.2)
				(max_length 1)
				(best_width_ratio 0.9)
				(max_width 2)
				(curved_edges yes)
				(filter_ratio 0.9)
				(enabled yes)
				(allow_two_segments yes)
				(prefer_zone_connections yes)
			)
		)
		(pad "2" smd roundrect
			(at 0.7 0 270)
			(size 0.8 1)
			(layers "F.Cu" "F.Mask" "F.Paste")
			(roundrect_rratio 0.2)
			(net 933 "Net-(D11-A)")
			(pinfunction "A")
			(pintype "passive")
			(teardrops
				(best_length_ratio 0.2)
				(max_length 1)
				(best_width_ratio 0.9)
				(max_width 2)
				(curved_edges yes)
				(filter_ratio 0.9)
				(enabled yes)
				(allow_two_segments yes)
				(prefer_zone_connections yes)
			)
		)
	)
	(footprint "antmicro-footprints:R_0402_1005Metric"
		(layer "F.Cu")
		(at 130.08 116.6 180)
		(descr "Resistor SMD 0402")
		(tags "resistor SMD 0402")
		(property "Reference" "R22"
			(at 0.780999 0.45 0)
			(layer "F.SilkS")
			(effects
				(font
					(size 0.7 0.7)
					(thickness 0.15)
				)
				(justify right top)
			)
		)
		(property "Value" "R_0R_0402"
			(at -1.011843 1.772046 0)
			(layer "F.Fab")
			(effects
				(font
					(size 0.7 0.7)
					(thickness 0.15)
				)
				(justify right top)
			)
		)
		(property "Datasheet" "https://industrial.panasonic.com/cdbs/www-data/pdf/RDA0000/AOA0000C301.pdf"
			(at 0 0 0)
			(layer "F.Fab")
			(hide yes)
			(effects
				(font
					(size 1.27 1.27)
					(thickness 0.15)
				)
			)
		)
		(property "Author" "Antmicro"
			(at 354.241 -58.059 90)
			(layer "F.Fab")
			(hide yes)
			(effects
				(font
					(size 1 1)
					(thickness 0.15)
				)
			)
		)
		(property "Current" "1A"
			(at 354.241 -58.059 90)
			(layer "F.Fab")
			(hide yes)
			(effects
				(font
					(size 1 1)
					(thickness 0.15)
				)
			)
		)
		(property "License" "Apache-2.0"
			(at 354.241 -58.059 90)
			(layer "F.Fab")
			(hide yes)
			(effects
				(font
					(size 1 1)
					(thickness 0.15)
				)
			)
		)
		(property "MPN" "ERJ2GE0R00X"
			(at 354.241 -58.059 90)
			(layer "F.Fab")
			(hide yes)
			(effects
				(font
					(size 1 1)
					(thickness 0.15)
				)
			)
		)
		(property "Manufacturer" "Panasonic"
			(at 354.241 -58.059 90)
			(layer "F.Fab")
			(hide yes)
			(effects
				(font
					(size 1 1)
					(thickness 0.15)
				)
			)
		)
		(property "Public" "False"
			(at 354.241 -58.059 90)
			(layer "F.Fab")
			(hide yes)
			(effects
				(font
					(size 1 1)
					(thickness 0.15)
				)
			)
		)
		(property "Tolerance" ""
			(at 354.241 -58.059 90)
			(layer "F.Fab")
			(hide yes)
			(effects
				(font
					(size 1 1)
					(thickness 0.15)
				)
			)
		)
		(property "Val" "0R"
			(at 354.241 -58.059 90)
			(layer "F.Fab")
			(hide yes)
			(effects
				(font
					(size 1 1)
					(thickness 0.15)
				)
			)
		)
		(sheetname "2xUSB3.0+RJ45")
		(sheetfile "usb3+rj45.kicad_sch")
		(attr smd)
		(fp_rect
			(start -0.925 -0.47)
			(end 0.925 0.47)
			(stroke
				(width 0.05)
				(type default)
			)
			(fill no)
			(layer "F.CrtYd")
		)
		(fp_rect
			(start -0.5 -0.25)
			(end 0.5 0.25)
			(stroke
				(width 0.15)
				(type solid)
			)
			(fill no)
			(layer "F.Fab")
		)
		(pad "1" smd roundrect
			(at -0.48 0 180)
			(size 0.59 0.64)
			(layers "F.Cu" "F.Mask" "F.Paste")
			(roundrect_rratio 0.25)
			(net 375 "/2xUSB3.0+RJ45/USB_2.D+")
			(pintype "passive")
			(teardrops
				(best_length_ratio 0.2)
				(max_length 1)
				(best_width_ratio 0.9)
				(max_width 2)
				(curved_edges yes)
				(filter_ratio 0.9)
				(enabled yes)
				(allow_two_segments yes)
				(prefer_zone_connections yes)
			)
		)
		(pad "2" smd roundrect
			(at 0.48 0 180)
			(size 0.59 0.64)
			(layers "F.Cu" "F.Mask" "F.Paste")
			(roundrect_rratio 0.25)
			(net 126 "/2xUSB3.0+RJ45/P2_D+")
			(pintype "passive")
			(teardrops
				(best_length_ratio 0.2)
				(max_length 1)
				(best_width_ratio 0.9)
				(max_width 2)
				(curved_edges yes)
				(filter_ratio 0.9)
				(enabled yes)
				(allow_two_segments yes)
				(prefer_zone_connections yes)
			)
		)
	)
	(footprint "antmicro-footprints:LED_0603_1608Metric_G"
		(layer "F.Cu")
		(at 201.70861 74.802163 90)
		(descr "LED SMD 0603 Green")
		(tags "LED SMD 0603 Green")
		(property "Reference" "D26"
			(at -1.1 -0.55 90)
			(layer "F.SilkS")
			(effects
				(font
					(size 0.7 0.7)
					(thickness 0.15)
				)
				(justify left bottom)
			)
		)
		(property "Value" "LED_G_0603_LTST-C190GKT"
			(at -0.001 1.599 90)
			(layer "F.Fab")
			(effects
				(font
					(size 0.7 0.7)
					(thickness 0.15)
				)
				(justify left bottom)
			)
		)
		(property "Datasheet" "https://media.digikey.com/pdf/Data%20Sheets/Lite-On%20PDFs/LTST-C190GKT.pdf"
			(at 0 0 90)
			(layer "F.Fab")
			(hide yes)
			(effects
				(font
					(size 1.27 1.27)
					(thickness 0.15)
				)
			)
		)
		(property "Author" "Antmicro"
			(at 276.510773 -126.906447 0)
			(layer "F.Fab")
			(hide yes)
			(effects
				(font
					(size 1 1)
					(thickness 0.15)
				)
			)
		)
		(property "Color" "Green"
			(at 276.510773 -126.906447 0)
			(layer "F.Fab")
			(hide yes)
			(effects
				(font
					(size 1 1)
					(thickness 0.15)
				)
			)
		)
		(property "License" "Apache-2.0"
			(at 276.510773 -126.906447 0)
			(layer "F.Fab")
			(hide yes)
			(effects
				(font
					(size 1 1)
					(thickness 0.15)
				)
			)
		)
		(property "MPN" "LTST-C190GKT"
			(at 276.510773 -126.906447 0)
			(layer "F.Fab")
			(hide yes)
			(effects
				(font
					(size 1 1)
					(thickness 0.15)
				)
			)
		)
		(property "Manufacturer" "Lite-On"
			(at 276.510773 -126.906447 0)
			(layer "F.Fab")
			(hide yes)
			(effects
				(font
					(size 1 1)
					(thickness 0.15)
				)
			)
		)
		(property "Public" "False"
			(at 276.510773 -126.906447 0)
			(layer "F.Fab")
			(hide yes)
			(effects
				(font
					(size 1 1)
					(thickness 0.15)
				)
			)
		)
		(sheetname "Power")
		(sheetfile "power.kicad_sch")
		(attr smd)
		(fp_line
			(start 0.22 -0.35)
			(end -0.22 -0.35)
			(stroke
				(width 0.15)
				(type solid)
			)
			(layer "F.SilkS")
		)
		(fp_line
			(start -1.18 -0.319)
			(end -1.18 0.321)
			(stroke
				(width 0.15)
				(type solid)
			)
			(layer "F.SilkS")
		)
		(fp_line
			(start 0.105328 0.001008)
			(end 0.24 0.001)
			(stroke
				(width 0.1)
				(type solid)
			)
			(layer "F.SilkS")
		)
		(fp_line
			(start -0.094672 0.001008)
			(end 0.105328 -0.198992)
			(stroke
				(width 0.1)
				(type solid)
			)
			(layer "F.SilkS")
		)
		(fp_line
			(start -0.094672 0.001008)
			(end -0.24 0.001008)
			(stroke
				(width 0.1)
				(type solid)
			)
			(layer "F.SilkS")
		)
		(fp_line
			(start 0.105328 0.201008)
			(end 0.105328 -0.198992)
			(stroke
				(width 0.1)
				(type solid)
			)
			(layer "F.SilkS")
		)
		(fp_line
			(start 0.105328 0.201008)
			(end -0.094672 0.001008)
			(stroke
				(width 0.1)
				(type solid)
			)
			(layer "F.SilkS")
		)
		(fp_line
			(start -0.094672 0.201008)
			(end -0.094672 -0.198992)
			(stroke
				(width 0.1)
				(type solid)
			)
			(layer "F.SilkS")
		)
		(fp_line
			(start 0.22 0.35)
			(end -0.22 0.35)
			(stroke
				(width 0.15)
				(type solid)
			)
			(layer "F.SilkS")
		)
		(fp_rect
			(start 1.25 0.65)
			(end -1.25 -0.65)
			(stroke
				(width 0.05)
				(type solid)
			)
			(fill no)
			(layer "F.CrtYd")
		)
		(fp_line
			(start 0.201 -0.202)
			(end -0.101 0)
			(stroke
				(width 0.15)
				(type solid)
			)
			(layer "F.Fab")
		)
		(fp_line
			(start -0.199 -0.202)
			(end -0.199 0.1)
			(stroke
				(width 0.15)
				(type solid)
			)
			(layer "F.Fab")
		)
		(fp_line
			(start 0.599 0)
			(end 0.201 0)
			(stroke
				(width 0.15)
				(type solid)
			)
			(layer "F.Fab")
		)
		(fp_line
			(start 0.201 0)
			(end 0.201 -0.202)
			(stroke
				(width 0.15)
				(type solid)
			)
			(layer "F.Fab")
		)
		(fp_line
			(start -0.101 0)
			(end 0.201 0.2)
			(stroke
				(width 0.15)
				(type solid)
			)
			(layer "F.Fab")
		)
		(fp_line
			(start -0.199 0)
			(end -0.597 0)
			(stroke
				(width 0.15)
				(type solid)
			)
			(layer "F.Fab")
		)
		(fp_line
			(start 0.201 0.2)
			(end 0.201 0)
			(stroke
				(width 0.15)
				(type solid)
			)
			(layer "F.Fab")
		)
		(fp_line
			(start -0.199 0.2)
			(end -0.199 0.1)
			(stroke
				(width 0.15)
				(type solid)
			)
			(layer "F.Fab")
		)
		(fp_rect
			(start 0.848 0.4)
			(end -0.85 -0.402)
			(stroke
				(width 0.15)
				(type solid)
			)
			(fill no)
			(layer "F.Fab")
		)
		(pad "1" smd roundrect
			(at -0.7 0 270)
			(size 0.8 1)
			(layers "F.Cu" "F.Mask" "F.Paste")
			(roundrect_rratio 0.2)
			(net 979 "Net-(D26-C)")
			(pinfunction "C")
			(pintype "passive")
			(teardrops
				(best_length_ratio 0.2)
				(max_length 1)
				(best_width_ratio 0.9)
				(max_width 2)
				(curved_edges yes)
				(filter_ratio 0.9)
				(enabled yes)
				(allow_two_segments yes)
				(prefer_zone_connections yes)
			)
		)
		(pad "2" smd roundrect
			(at 0.7 0 270)
			(size 0.8 1)
			(layers "F.Cu" "F.Mask" "F.Paste")
			(roundrect_rratio 0.2)
			(net 62 "+12V_AON")
			(pinfunction "A")
			(pintype "passive")
			(teardrops
				(best_length_ratio 0.2)
				(max_length 1)
				(best_width_ratio 0.9)
				(max_width 2)
				(curved_edges yes)
				(filter_ratio 0.9)
				(enabled yes)
				(allow_two_segments yes)
				(prefer_zone_connections yes)
			)
		)
	)
	(footprint "antmicro-footprints:C_0402_1005Metric"
		(layer "F.Cu")
		(at 240.8 132.36 -90)
		(descr "Capacitor SMD 0402")
		(tags "capacitor SMD 0402")
		(property "Reference" "C216"
			(at 0.8 0.37 90)
			(layer "F.SilkS")
			(effects
				(font
					(size 0.7 0.7)
					(thickness 0.15)
				)
				(justify right top)
			)
		)
		(property "Value" "C_100n_0402"
			(at -1.022927 2.155213 90)
			(layer "F.Fab")
			(effects
				(font
					(size 0.7 0.7)
					(thickness 0.15)
				)
				(justify right top)
			)
		)
		(property "Datasheet" "https://www.murata.com/products/productdetail?partno=GRM155R61H104KE14%23"
			(at 0 0 90)
			(layer "F.Fab")
			(hide yes)
			(effects
				(font
					(size 1.27 1.27)
					(thickness 0.15)
				)
			)
		)
		(property "MPN" "GRM155R61H104KE14D"
			(at 0 0 270)
			(unlocked yes)
			(layer "F.Fab")
			(hide yes)
			(effects
				(font
					(size 1 1)
					(thickness 0.15)
				)
			)
		)
		(property "Manufacturer" "Murata"
			(at 0 0 270)
			(unlocked yes)
			(layer "F.Fab")
			(hide yes)
			(effects
				(font
					(size 1 1)
					(thickness 0.15)
				)
			)
		)
		(property "License" "Apache-2.0"
			(at 0 0 270)
			(unlocked yes)
			(layer "F.Fab")
			(hide yes)
			(effects
				(font
					(size 1 1)
					(thickness 0.15)
				)
			)
		)
		(property "Author" "Antmicro"
			(at 0 0 270)
			(unlocked yes)
			(layer "F.Fab")
			(hide yes)
			(effects
				(font
					(size 1 1)
					(thickness 0.15)
				)
			)
		)
		(property "Val" "100n"
			(at 0 0 270)
			(unlocked yes)
			(layer "F.Fab")
			(hide yes)
			(effects
				(font
					(size 1 1)
					(thickness 0.15)
				)
			)
		)
		(property "Voltage" "50V"
			(at 0 0 270)
			(unlocked yes)
			(layer "F.Fab")
			(hide yes)
			(effects
				(font
					(size 1 1)
					(thickness 0.15)
				)
			)
		)
		(property "Dielectric" "X5R"
			(at 0 0 270)
			(unlocked yes)
			(layer "F.Fab")
			(hide yes)
			(effects
				(font
					(size 1 1)
					(thickness 0.15)
				)
			)
		)
		(property "Public" "False"
			(at 0 0 270)
			(unlocked yes)
			(layer "F.Fab")
			(hide yes)
			(effects
				(font
					(size 1 1)
					(thickness 0.15)
				)
			)
		)
		(sheetname "Com Express 7 MGMT")
		(sheetfile "com_express_7_mgmt.kicad_sch")
		(attr smd)
		(fp_rect
			(start -0.925 -0.47)
			(end 0.925 0.47)
			(stroke
				(width 0.05)
				(type default)
			)
			(fill no)
			(layer "F.CrtYd")
		)
		(fp_line
			(start -0.494 0.248)
			(end -0.494 -0.25)
			(stroke
				(width 0.15)
				(type solid)
			)
			(layer "F.Fab")
		)
		(fp_line
			(start 0.504 0.248)
			(end -0.494 0.248)
			(stroke
				(width 0.15)
				(type solid)
			)
			(layer "F.Fab")
		)
		(fp_line
			(start -0.494 -0.25)
			(end 0.504 -0.25)
			(stroke
				(width 0.15)
				(type solid)
			)
			(layer "F.Fab")
		)
		(fp_line
			(start 0.504 -0.25)
			(end 0.504 0.248)
			(stroke
				(width 0.15)
				(type solid)
			)
			(layer "F.Fab")
		)
		(pad "1" smd roundrect
			(at -0.48 0 270)
			(size 0.59 0.64)
			(layers "F.Cu" "F.Mask" "F.Paste")
			(roundrect_rratio 0.25)
			(net 1 "GND")
			(pintype "passive")
			(teardrops
				(best_length_ratio 0.2)
				(max_length 1)
				(best_width_ratio 0.9)
				(max_width 2)
				(curved_edges yes)
				(filter_ratio 0.9)
				(enabled yes)
				(allow_two_segments yes)
				(prefer_zone_connections yes)
			)
		)
		(pad "2" smd roundrect
			(at 0.48 0 270)
			(size 0.59 0.64)
			(layers "F.Cu" "F.Mask" "F.Paste")
			(roundrect_rratio 0.25)
			(net 533 "/Com Express 7 MGMT/PSON")
			(pintype "passive")
			(teardrops
				(best_length_ratio 0.2)
				(max_length 1)
				(best_width_ratio 0.9)
				(max_width 2)
				(curved_edges yes)
				(filter_ratio 0.9)
				(enabled yes)
				(allow_two_segments yes)
				(prefer_zone_connections yes)
			)
		)
	)
	(footprint "antmicro-footprints:TP_SMD_0.75mm"
		(layer "F.Cu")
		(at 147.25 129.56)
		(property "Reference" "TP76"
			(at 0.45 -1.25 90)
			(layer "F.SilkS")
			(effects
				(font
					(size 0.7 0.7)
					(thickness 0.15)
				)
				(justify left bottom)
			)
		)
		(property "Value" "TP_0.75mm_SMD"
			(at 0 1.2 0)
			(layer "F.Fab")
			(effects
				(font
					(size 0.7 0.7)
					(thickness 0.15)
				)
				(justify left bottom)
			)
		)
		(property "Author" "Antmicro"
			(at 0 0 0)
			(layer "F.Fab")
			(hide yes)
			(effects
				(font
					(size 1 1)
					(thickness 0.15)
				)
			)
		)
		(property "License" "Apache-2.0"
			(at 0 0 0)
			(layer "F.Fab")
			(hide yes)
			(effects
				(font
					(size 1 1)
					(thickness 0.15)
				)
			)
		)
		(property "MPN" ""
			(at 0 0 0)
			(layer "F.Fab")
			(hide yes)
			(effects
				(font
					(size 1 1)
					(thickness 0.15)
				)
			)
		)
		(property "Manufacturer" ""
			(at 0 0 0)
			(layer "F.Fab")
			(hide yes)
			(effects
				(font
					(size 1 1)
					(thickness 0.15)
				)
			)
		)
		(property "Public" "False"
			(at 0 0 0)
			(layer "F.Fab")
			(hide yes)
			(effects
				(font
					(size 1 1)
					(thickness 0.15)
				)
			)
		)
		(sheetname "KR to SFI #1")
		(sheetfile "kr_sfi.kicad_sch")
		(attr exclude_from_pos_files exclude_from_bom)
		(fp_circle
			(center 0 0)
			(end 0.475 0)
			(stroke
				(width 0.05)
				(type default)
			)
			(fill no)
			(layer "F.CrtYd")
		)
		(pad "1" smd circle
			(at 0 0)
			(size 0.75 0.75)
			(layers "F.Cu" "F.Mask")
			(net 739 "Net-(U43B-LS_OK_{OUT_B})")
			(pinfunction "1")
			(pintype "passive")
			(teardrops
				(best_length_ratio 0.4)
				(max_length 1)
				(best_width_ratio 0.9)
				(max_width 2)
				(curved_edges yes)
				(filter_ratio 0.9)
				(enabled yes)
				(allow_two_segments yes)
				(prefer_zone_connections yes)
			)
		)
	)
)
